# S9S_MB_2U (Grand Teton) — schematic netlist excerpt (pin names and nets, part order shuffled) for the footprints in the layout excerpt that follows; sources: Cadence DE-HDL packaged netlist, KiCad conversion of 03242023_DA0F0TMBIJ0_F0T_Motherboard_J_brd_V01_OCP.brd

PC3  Q_CAPP  270UF 16V 20% OSCON  pkg THLF  page 259 : A = SW_P3V3_AUX_FLT ; B = GND
R2520  Q_RES  0 5% CHIP  pkg 0402LF  page 284 : A = SMB_VR_3V3AUX_SCL_R3 ; B = SMB_CLK_PVCCIN_CPU1

PR3  Q_RES_4P_12  0.003 1% EMPTY  pkg R2512_4P_H41  page 304
  \1\  = P12V_PSU
  \2\  = P12V_MAIN_R_0
  \3\  = P12V_HSC_SENSE1_P
  \4\  = P12V_HSC_SENSE1_N

(kicad_pcb
	(version 20260206)
	(generator "pcbnew")
	(generator_version "10.0")
	(general
		(thickness 1.6)
		(legacy_teardrops no)
	)
	(paper "A4")
	(title_block
		(title "03242023_DA0F0TMBIJ0_F0T_Motherboard_J_brd_V01_OCP.brd")
		(comment 1 "Grand Teton / footprints 2166-2168 of 6105")
	)
	(layers
		(0 "F.Cu" signal "TOP")
		(4 "In1.Cu" signal "GND")
		(6 "In2.Cu" signal "IN1")
		(8 "In3.Cu" signal "GND1")
		(10 "In4.Cu" signal "IN2")
		(12 "In5.Cu" signal "GND2")
		(14 "In6.Cu" signal "IN3")
		(16 "In7.Cu" signal "GND3")
		(18 "In8.Cu" signal "VCC")
		(20 "In9.Cu" signal "VCC1")
		(22 "In10.Cu" signal "GND4")
		(24 "In11.Cu" signal "IN4")
		(26 "In12.Cu" signal "GND5")
		(28 "In13.Cu" signal "IN5")
		(30 "In14.Cu" signal "GND6")
		(32 "In15.Cu" signal "IN6")
		(34 "In16.Cu" signal "GND7")
		(2 "B.Cu" signal "BOTTOM")
		(9 "F.Adhes" user "F.Adhesive")
		(11 "B.Adhes" user "B.Adhesive")
		(13 "F.Paste" user "Package Geometry/Pastemask Top")
		(15 "B.Paste" user "Package Geometry/Pastemask Bottom")
		(5 "F.SilkS" user "Ref Des/Silkscreen Top")
		(7 "B.SilkS" user "Ref Des/Silkscreen Bottom")
		(1 "F.Mask" user "Board Geometry/Soldermask Top")
		(3 "B.Mask" user "Board Geometry/Soldermask Bottom")
		(17 "Dwgs.User" user "User.Drawings")
		(19 "Cmts.User" user "User.Comments")
		(21 "Eco1.User" user "User.Eco1")
		(23 "Eco2.User" user "User.Eco2")
		(25 "Edge.Cuts" user "Board Geometry/Outline")
		(27 "Margin" user)
		(31 "F.CrtYd" user "Package Geometry/Place Bound Top")
		(29 "B.CrtYd" user "Package Geometry/Place Bound Bottom")
		(35 "F.Fab" user "Ref Des/Assembly Top")
		(33 "B.Fab" user "Ref Des/Assembly Bottom")
	)
	(footprint ""
		(layer "F.Cu")
		(at 277.859744 -407.401776 -90)
		(property "Reference" "PR3"
			(at 0 0 270)
			(layer "F.SilkS")
			(hide yes)
			(effects
				(font
					(size 1.27 1.27)
				)
			)
		)
		(property "Value" ""
			(at 0 0 270)
			(layer "F.Fab")
			(effects
				(font
					(size 1.27 1.27)
				)
			)
		)
		(duplicate_pad_numbers_are_jumpers no)
		(fp_line
			(start -4.0386 1.7526)
			(end -4.0386 -1.7526)
			(stroke
				(width 0.1524)
				(type default)
			)
			(layer "F.SilkS")
		)
		(fp_line
			(start 4.0386 1.7526)
			(end -4.0386 1.7526)
			(stroke
				(width 0.1524)
				(type default)
			)
			(layer "F.SilkS")
		)
		(fp_line
			(start -4.0386 -1.7526)
			(end 4.0386 -1.7526)
			(stroke
				(width 0.1524)
				(type default)
			)
			(layer "F.SilkS")
		)
		(fp_line
			(start 4.0386 -1.7526)
			(end 4.0386 1.7526)
			(stroke
				(width 0.1524)
				(type default)
			)
			(layer "F.SilkS")
		)
		(fp_line
			(start -4.0386 1.7526)
			(end -4.0386 -1.7526)
			(stroke
				(width 0.1)
				(type default)
			)
			(layer "F.Fab")
		)
		(fp_line
			(start 4.0386 1.7526)
			(end -4.0386 1.7526)
			(stroke
				(width 0.1)
				(type default)
			)
			(layer "F.Fab")
		)
		(fp_line
			(start -4.0386 -1.7526)
			(end 4.0386 -1.7526)
			(stroke
				(width 0.1)
				(type default)
			)
			(layer "F.Fab")
		)
		(fp_line
			(start 4.0386 -1.7526)
			(end 4.0386 1.7526)
			(stroke
				(width 0.1)
				(type default)
			)
			(layer "F.Fab")
		)
		(pad "1" smd circle
			(at -3.700018 0 180)
			(size 0 0)
			(layers "F.Cu" "F.Mask" "F.Paste")
			(net "P12V_PSU")
		)
		(pad "2" smd circle
			(at 3.700018 0)
			(size 0 0)
			(layers "F.Cu" "F.Mask" "F.Paste")
			(net "P12V_MAIN_R_0")
		)
		(pad "3" smd rect
			(at -2.70002 0)
			(size 0.4064 1.1176)
			(layers "F.Cu" "F.Mask" "F.Paste")
			(net "P12V_HSC_SENSE1_P")
		)
		(pad "4" smd rect
			(at 2.70002 0)
			(size 0.4064 1.1176)
			(layers "F.Cu" "F.Mask" "F.Paste")
			(net "P12V_HSC_SENSE1_N")
		)
	)
	(footprint ""
		(layer "F.Cu")
		(at 463.90687 -68.519802 90)
		(property "Reference" "PC3"
			(at 0 0 90)
			(layer "F.SilkS")
			(hide yes)
			(effects
				(font
					(size 1.27 1.27)
				)
			)
		)
		(property "Value" ""
			(at 0 0 90)
			(layer "F.Fab")
			(effects
				(font
					(size 1.27 1.27)
				)
			)
		)
		(duplicate_pad_numbers_are_jumpers no)
		(fp_line
			(start -3.400044 1.249934)
			(end 3.400044 1.249934)
			(stroke
				(width 0.1524)
				(type default)
			)
			(layer "F.SilkS")
		)
		(fp_circle
			(center 0 1.249934)
			(end 0 4.649978)
			(stroke
				(width 0.1524)
				(type default)
			)
			(fill no)
			(layer "F.SilkS")
		)
		(fp_poly
			(pts
				(arc
					(start -3.400044 1.249934)
					(mid 0 4.649978)
					(end 3.400044 1.249934)
				)
			)
			(stroke
				(width 0)
				(type default)
			)
			(fill yes)
			(layer "F.SilkS")
		)
		(fp_circle
			(center 0 1.249934)
			(end 0 4.649978)
			(stroke
				(width 0.1)
				(type default)
			)
			(fill no)
			(layer "F.Fab")
		)
		(pad "1" thru_hole rect
			(at 0 0 90)
			(size 1.524 1.524)
			(drill 1.016)
			(layers "*.Cu" "*.Mask")
			(remove_unused_layers no)
			(net "SW_P3V3_AUX_FLT")
			(clearance 0)
			(padstack
				(mode front_inner_back)
				(layer "Inner"
					(shape circle)
					(size 1.524 1.524)
					(clearance 0)
				)
				(layer "B.Cu"
					(shape rect)
					(size 1.524 1.524)
					(clearance 0)
				)
			)
		)
		(pad "2" thru_hole circle
			(at 0 2.500122 90)
			(size 1.524 1.524)
			(drill 1.016)
			(layers "*.Cu" "*.Mask")
			(remove_unused_layers no)
			(net "GND")
			(clearance 0)
		)
	)
	(footprint ""
		(layer "F.Cu")
		(at 103.306372 -362.602526)
		(property "Reference" "R2520"
			(at 0 0 0)
			(layer "F.SilkS")
			(hide yes)
			(effects
				(font
					(size 1.27 1.27)
				)
			)
		)
		(property "Value" ""
			(at 0 0 0)
			(layer "F.Fab")
			(effects
				(font
					(size 1.27 1.27)
				)
			)
		)
		(duplicate_pad_numbers_are_jumpers no)
		(fp_line
			(start -0.7874 -0.4064)
			(end 0.7874 -0.4064)
			(stroke
				(width 0.1524)
				(type default)
			)
			(layer "F.SilkS")
		)
		(fp_line
			(start -0.7874 0.4064)
			(end -0.7874 -0.4064)
			(stroke
				(width 0.1524)
				(type default)
			)
			(layer "F.SilkS")
		)
		(fp_line
			(start 0.7874 -0.4064)
			(end 0.7874 0.4064)
			(stroke
				(width 0.1524)
				(type default)
			)
			(layer "F.SilkS")
		)
		(fp_line
			(start 0.7874 0.4064)
			(end -0.7874 0.4064)
			(stroke
				(width 0.1524)
				(type default)
			)
			(layer "F.SilkS")
		)
		(fp_line
			(start -0.67945 -0.305054)
			(end -0.12065 -0.305054)
			(stroke
				(width 0.1)
				(type default)
			)
			(layer "F.Fab")
		)
		(fp_line
			(start -0.67945 0.3048)
			(end -0.67945 -0.305054)
			(stroke
				(width 0.1)
				(type default)
			)
			(layer "F.Fab")
		)
		(fp_line
			(start -0.12065 -0.305054)
			(end -0.12065 -0.2794)
			(stroke
				(width 0.1)
				(type default)
			)
			(layer "F.Fab")
		)
		(fp_line
			(start -0.12065 -0.2794)
			(end 0.12065 -0.2794)
			(stroke
				(width 0.1)
				(type default)
			)
			(layer "F.Fab")
		)
		(fp_line
			(start -0.12065 0.2794)
			(end -0.12065 0.3048)
			(stroke
				(width 0.1)
				(type default)
			)
			(layer "F.Fab")
		)
		(fp_line
			(start -0.12065 0.3048)
			(end -0.67945 0.3048)
			(stroke
				(width 0.1)
				(type default)
			)
			(layer "F.Fab")
		)
		(fp_line
			(start 0.120396 0.2794)
			(end -0.12065 0.2794)
			(stroke
				(width 0.1)
				(type default)
			)
			(layer "F.Fab")
		)
		(fp_line
			(start 0.120396 0.3048)
			(end 0.120396 0.2794)
			(stroke
				(width 0.1)
				(type default)
			)
			(layer "F.Fab")
		)
		(fp_line
			(start 0.12065 -0.3048)
			(end 0.67945 -0.3048)
			(stroke
				(width 0.1)
				(type default)
			)
			(layer "F.Fab")
		)
		(fp_line
			(start 0.12065 -0.2794)
			(end 0.12065 -0.3048)
			(stroke
				(width 0.1)
				(type default)
			)
			(layer "F.Fab")
		)
		(fp_line
			(start 0.67945 -0.3048)
			(end 0.67945 0.3048)
			(stroke
				(width 0.1)
				(type default)
			)
			(layer "F.Fab")
		)
		(fp_line
			(start 0.67945 0.3048)
			(end 0.120396 0.3048)
			(stroke
				(width 0.1)
				(type default)
			)
			(layer "F.Fab")
		)
		(pad "1" smd circle
			(at -0.40005 0)
			(size 0 0)
			(layers "F.Cu" "F.Mask" "F.Paste")
			(net "SMB_VR_3V3AUX_SCL_R3")
		)
		(pad "2" smd circle
			(at 0.40005 0)
			(size 0 0)
			(layers "F.Cu" "F.Mask" "F.Paste")
			(net "SMB_CLK_PVCCIN_CPU1")
		)
	)
)
